# SCM (Grand Teton) — schematic netlist excerpt (pin names and nets, part order shuffled) for the footprints in the layout excerpt that follows; sources: Cadence DE-HDL packaged netlist, KiCad conversion of 12092022_DA0F0TMDCD0_F0T_Management_Board_D_brd_V3_OCP.brd

R653  Q_RES  33.2 1% EMPTY  pkg 0402LF  page 21 : A = BMC_EMMC_DT4 ; B = EMMC_DT4_R

X5  TP_TDR_4P_FTS  TP_TDR_4P_DIP EMPTY  pkg TH  page 60
  S1  = TDR_DIFF_85_IN4_DP
  P1  = GND_P1
  P2  = GND_P1
  S2  = TDR_DIFF_85_IN4_DN

(kicad_pcb
	(version 20260206)
	(generator "pcbnew")
	(generator_version "10.0")
	(general
		(thickness 1.6)
		(legacy_teardrops no)
	)
	(paper "A4")
	(title_block
		(title "12092022_DA0F0TMDCD0_F0T_Management_Board_D_brd_V3_OCP.brd")
		(comment 1 "Grand Teton / footprints 725-726 of 1440")
	)
	(layers
		(0 "F.Cu" signal "TOP")
		(4 "In1.Cu" signal "GND")
		(6 "In2.Cu" signal "IN1")
		(8 "In3.Cu" signal "GND1")
		(10 "In4.Cu" signal "IN2")
		(12 "In5.Cu" signal "VCC")
		(14 "In6.Cu" signal "VCC1")
		(16 "In7.Cu" signal "IN3")
		(18 "In8.Cu" signal "GND2")
		(20 "In9.Cu" signal "IN4")
		(22 "In10.Cu" signal "GND3")
		(2 "B.Cu" signal "BOTTOM")
		(9 "F.Adhes" user "F.Adhesive")
		(11 "B.Adhes" user "B.Adhesive")
		(13 "F.Paste" user "Package Geometry/Pastemask Top")
		(15 "B.Paste" user "Package Geometry/Pastemask Bottom")
		(5 "F.SilkS" user "Ref Des/Silkscreen Top")
		(7 "B.SilkS" user "Ref Des/Silkscreen Bottom")
		(1 "F.Mask" user "Board Geometry/Soldermask Top")
		(3 "B.Mask" user "Board Geometry/Soldermask Bottom")
		(17 "Dwgs.User" user "User.Drawings")
		(19 "Cmts.User" user "User.Comments")
		(21 "Eco1.User" user "User.Eco1")
		(23 "Eco2.User" user "User.Eco2")
		(25 "Edge.Cuts" user "Board Geometry/Outline")
		(27 "Margin" user)
		(31 "F.CrtYd" user "Package Geometry/Place Bound Top")
		(29 "B.CrtYd" user "Package Geometry/Place Bound Bottom")
		(35 "F.Fab" user "Ref Des/Assembly Top")
		(33 "B.Fab" user "Ref Des/Assembly Bottom")
	)
	(footprint ""
		(layer "F.Cu")
		(at 112.014 -50.8 90)
		(property "Reference" "X5"
			(at -0.0508 5.50037 90)
			(unlocked yes)
			(layer "F.SilkS")
			(effects
				(font
					(size 0.7874 0.5842)
					(thickness 0.1524)
				)
				(justify left)
			)
		)
		(property "Value" ""
			(at 0 0 90)
			(layer "F.Fab")
			(effects
				(font
					(size 1.27 1.27)
				)
			)
		)
		(property "Device Type" "TP_TDR_4P_FTS_TH-TP_TDR_4P_DIPA"
			(at 1.30175 1.27 180)
			(unlocked yes)
			(layer "F.Fab")
			(hide yes)
			(effects
				(font
					(size 0.635 0.4064)
					(thickness 0.1524)
				)
			)
		)
		(property "User Part Number" "N_A"
			(at 1.30175 1.27 180)
			(unlocked yes)
			(layer "Cmts.User")
			(hide yes)
			(effects
				(font
					(size 0.635 0.4064)
					(thickness 0.1524)
				)
			)
		)
		(duplicate_pad_numbers_are_jumpers no)
		(fp_line
			(start 2.54 -1.27)
			(end 0 -1.27)
			(stroke
				(width 0.1524)
				(type default)
			)
			(layer "F.SilkS")
		)
		(fp_line
			(start 0 -1.27)
			(end 0 -0.635)
			(stroke
				(width 0.1524)
				(type default)
			)
			(layer "F.SilkS")
		)
		(fp_line
			(start 2.54 -1.1303)
			(end 2.54 -1.27)
			(stroke
				(width 0.1524)
				(type default)
			)
			(layer "F.SilkS")
		)
		(fp_line
			(start 0 0.635)
			(end 0 1.905)
			(stroke
				(width 0.1524)
				(type default)
			)
			(layer "F.SilkS")
		)
		(fp_line
			(start 2.54 1.4097)
			(end 2.54 1.1303)
			(stroke
				(width 0.1524)
				(type default)
			)
			(layer "F.SilkS")
		)
		(fp_line
			(start 0 3.175)
			(end 0 3.81)
			(stroke
				(width 0.1524)
				(type default)
			)
			(layer "F.SilkS")
		)
		(fp_line
			(start 2.54 3.81)
			(end 2.54 3.6703)
			(stroke
				(width 0.1524)
				(type default)
			)
			(layer "F.SilkS")
		)
		(fp_line
			(start 0 3.81)
			(end 2.54 3.81)
			(stroke
				(width 0.1524)
				(type default)
			)
			(layer "F.SilkS")
		)
		(fp_poly
			(pts
				(xy -0.761746 0) (xy -2.285746 -0.762) (xy -2.285746 0.762)
			)
			(stroke
				(width 0)
				(type default)
			)
			(fill yes)
			(layer "F.SilkS")
		)
		(fp_line
			(start 2.54 -1.27)
			(end 0 -1.27)
			(stroke
				(width 0.1)
				(type default)
			)
			(layer "F.Fab")
		)
		(fp_line
			(start 0 -1.27)
			(end 0 3.81)
			(stroke
				(width 0.1)
				(type default)
			)
			(layer "F.Fab")
		)
		(fp_line
			(start 2.54 3.81)
			(end 2.54 -1.27)
			(stroke
				(width 0.1)
				(type default)
			)
			(layer "F.Fab")
		)
		(fp_line
			(start 0 3.81)
			(end 2.54 3.81)
			(stroke
				(width 0.1)
				(type default)
			)
			(layer "F.Fab")
		)
		(fp_poly
			(pts
				(xy -0.761746 0) (xy -2.285746 -0.762) (xy -2.285746 0.762)
			)
			(stroke
				(width 0)
				(type default)
			)
			(fill yes)
			(layer "F.Fab")
		)
		(pad "1" thru_hole circle
			(at 0 0 90)
			(size 1.0033 1.0033)
			(drill 0.249936)
			(layers "*.Cu" "*.Mask")
			(remove_unused_layers no)
			(net "TDR_DIFF_85_IN4_DP")
			(clearance 0.10795)
			(thermal_gap 0.10795)
			(padstack
				(mode front_inner_back)
				(layer "Inner"
					(shape circle)
					(size 0.8001 0.8001)
					(clearance 0.1524)
				)
				(layer "B.Cu"
					(shape circle)
					(size 1.0033 1.0033)
					(clearance 0.10795)
				)
			)
		)
		(pad "2" thru_hole circle
			(at 2.54 0 90)
			(size 1.9939 1.9939)
			(drill 0.249936)
			(layers "*.Cu" "*.Mask")
			(remove_unused_layers no)
			(net "GND_P1")
			(clearance 0.10795)
			(thermal_gap 0.10795)
			(padstack
				(mode front_inner_back)
				(layer "Inner"
					(shape circle)
					(size 0.8001 0.8001)
					(clearance 0.1524)
				)
				(layer "B.Cu"
					(shape circle)
					(size 1.9939 1.9939)
					(clearance 0.10795)
				)
			)
		)
		(pad "3" thru_hole circle
			(at 2.54 2.54 90)
			(size 1.9939 1.9939)
			(drill 0.249936)
			(layers "*.Cu" "*.Mask")
			(remove_unused_layers no)
			(net "GND_P1")
			(clearance 0.10795)
			(thermal_gap 0.10795)
			(padstack
				(mode front_inner_back)
				(layer "Inner"
					(shape circle)
					(size 0.8001 0.8001)
					(clearance 0.1524)
				)
				(layer "B.Cu"
					(shape circle)
					(size 1.9939 1.9939)
					(clearance 0.10795)
				)
			)
		)
		(pad "4" thru_hole circle
			(at 0 2.54 90)
			(size 1.0033 1.0033)
			(drill 0.249936)
			(layers "*.Cu" "*.Mask")
			(remove_unused_layers no)
			(net "TDR_DIFF_85_IN4_DN")
			(clearance 0.10795)
			(thermal_gap 0.10795)
			(padstack
				(mode front_inner_back)
				(layer "Inner"
					(shape circle)
					(size 0.8001 0.8001)
					(clearance 0.1524)
				)
				(layer "B.Cu"
					(shape circle)
					(size 1.0033 1.0033)
					(clearance 0.10795)
				)
			)
		)
	)
	(footprint ""
		(layer "F.Cu")
		(at 32.70504 -70.536054 90)
		(property "Reference" "R653"
			(at 0 0 90)
			(layer "F.SilkS")
			(hide yes)
			(effects
				(font
					(size 1.27 1.27)
				)
			)
		)
		(property "Value" ""
			(at 0 0 90)
			(layer "F.Fab")
			(effects
				(font
					(size 1.27 1.27)
				)
			)
		)
		(duplicate_pad_numbers_are_jumpers no)
		(fp_line
			(start 0.7874 -0.4064)
			(end 0.7874 0.4064)
			(stroke
				(width 0.1524)
				(type default)
			)
			(layer "F.SilkS")
		)
		(fp_line
			(start -0.7874 -0.4064)
			(end 0.7874 -0.4064)
			(stroke
				(width 0.1524)
				(type default)
			)
			(layer "F.SilkS")
		)
		(fp_line
			(start 0.7874 0.4064)
			(end -0.7874 0.4064)
			(stroke
				(width 0.1524)
				(type default)
			)
			(layer "F.SilkS")
		)
		(fp_line
			(start -0.7874 0.4064)
			(end -0.7874 -0.4064)
			(stroke
				(width 0.1524)
				(type default)
			)
			(layer "F.SilkS")
		)
		(fp_line
			(start -0.12065 -0.305054)
			(end -0.12065 -0.2794)
			(stroke
				(width 0.1)
				(type default)
			)
			(layer "F.Fab")
		)
		(fp_line
			(start -0.67945 -0.305054)
			(end -0.12065 -0.305054)
			(stroke
				(width 0.1)
				(type default)
			)
			(layer "F.Fab")
		)
		(fp_line
			(start 0.67945 -0.3048)
			(end 0.67945 0.3048)
			(stroke
				(width 0.1)
				(type default)
			)
			(layer "F.Fab")
		)
		(fp_line
			(start 0.12065 -0.3048)
			(end 0.67945 -0.3048)
			(stroke
				(width 0.1)
				(type default)
			)
			(layer "F.Fab")
		)
		(fp_line
			(start 0.12065 -0.2794)
			(end 0.12065 -0.3048)
			(stroke
				(width 0.1)
				(type default)
			)
			(layer "F.Fab")
		)
		(fp_line
			(start -0.12065 -0.2794)
			(end 0.12065 -0.2794)
			(stroke
				(width 0.1)
				(type default)
			)
			(layer "F.Fab")
		)
		(fp_line
			(start 0.120396 0.2794)
			(end -0.12065 0.2794)
			(stroke
				(width 0.1)
				(type default)
			)
			(layer "F.Fab")
		)
		(fp_line
			(start -0.12065 0.2794)
			(end -0.12065 0.3048)
			(stroke
				(width 0.1)
				(type default)
			)
			(layer "F.Fab")
		)
		(fp_line
			(start 0.67945 0.3048)
			(end 0.120396 0.3048)
			(stroke
				(width 0.1)
				(type default)
			)
			(layer "F.Fab")
		)
		(fp_line
			(start 0.120396 0.3048)
			(end 0.120396 0.2794)
			(stroke
				(width 0.1)
				(type default)
			)
			(layer "F.Fab")
		)
		(fp_line
			(start -0.12065 0.3048)
			(end -0.67945 0.3048)
			(stroke
				(width 0.1)
				(type default)
			)
			(layer "F.Fab")
		)
		(fp_line
			(start -0.67945 0.3048)
			(end -0.67945 -0.305054)
			(stroke
				(width 0.1)
				(type default)
			)
			(layer "F.Fab")
		)
		(pad "1" smd circle
			(at -0.40005 0 90)
			(size 0 0)
			(layers "F.Cu" "F.Mask" "F.Paste")
			(net "BMC_EMMC_DT4")
		)
		(pad "2" smd circle
			(at 0.40005 0 90)
			(size 0 0)
			(layers "F.Cu" "F.Mask" "F.Paste")
			(net "EMMC_DT4_R")
		)
	)
)
